(kicad_pcb
	(version 20260206)
	(generator "pcbnew")
	(generator_version "10.0")
	(general
		(thickness 1.6)
		(legacy_teardrops no)
	)
	(paper "A4")
	(title_block
		(title "01162023_DA0F0TEBIF0_F0T_Expander_BD_F_brd_V02_OCP.brd")
		(comment 1 "Grand Teton / footprints 685-691 of 9728")
	)
	(layers
		(0 "F.Cu" signal "TOP")
		(4 "In1.Cu" signal "GND")
		(6 "In2.Cu" signal "VCC")
		(8 "In3.Cu" signal "VCC1")
		(10 "In4.Cu" signal "GND1")
		(12 "In5.Cu" signal "IN1")
		(14 "In6.Cu" signal "GND2")
		(16 "In7.Cu" signal "IN2")
		(18 "In8.Cu" signal "GND3")
		(20 "In9.Cu" signal "IN3")
		(22 "In10.Cu" signal "GND4")
		(24 "In11.Cu" signal "IN4")
		(26 "In12.Cu" signal "GND5")
		(28 "In13.Cu" signal "IN5")
		(30 "In14.Cu" signal "GND6")
		(32 "In15.Cu" signal "IN6")
		(34 "In16.Cu" signal "GND7")
		(2 "B.Cu" signal "BOTTOM")
		(9 "F.Adhes" user "F.Adhesive")
		(11 "B.Adhes" user "B.Adhesive")
		(13 "F.Paste" user "Package Geometry/Pastemask Top")
		(15 "B.Paste" user "Package Geometry/Pastemask Bottom")
		(5 "F.SilkS" user "Ref Des/Silkscreen Top")
		(7 "B.SilkS" user "Ref Des/Silkscreen Bottom")
		(1 "F.Mask" user "Board Geometry/Soldermask Top")
		(3 "B.Mask" user "Board Geometry/Soldermask Bottom")
		(17 "Dwgs.User" user "User.Drawings")
		(19 "Cmts.User" user "User.Comments")
		(21 "Eco1.User" user "User.Eco1")
		(23 "Eco2.User" user "User.Eco2")
		(25 "Edge.Cuts" user "Board Geometry/Outline")
		(27 "Margin" user)
		(31 "F.CrtYd" user "Package Geometry/Place Bound Top")
		(29 "B.CrtYd" user "Package Geometry/Place Bound Bottom")
		(35 "F.Fab" user "Ref Des/Assembly Top")
		(33 "B.Fab" user "Ref Des/Assembly Bottom")
	)
	(footprint ""
		(layer "F.Cu")
		(at 319.191386 -96.811592 -90)
		(property "Reference" "R736"
			(at 0 0 270)
			(layer "F.SilkS")
			(hide yes)
			(effects
				(font
					(size 1.27 1.27)
				)
			)
		)
		(property "Value" ""
			(at 0 0 270)
			(layer "F.Fab")
			(effects
				(font
					(size 1.27 1.27)
				)
			)
		)
		(duplicate_pad_numbers_are_jumpers no)
		(fp_line
			(start -0.7874 0.4064)
			(end -0.7874 -0.4064)
			(stroke
				(width 0.1524)
				(type default)
			)
			(layer "F.SilkS")
		)
		(fp_line
			(start 0.7874 0.4064)
			(end -0.7874 0.4064)
			(stroke
				(width 0.1524)
				(type default)
			)
			(layer "F.SilkS")
		)
		(fp_line
			(start -0.7874 -0.4064)
			(end 0.7874 -0.4064)
			(stroke
				(width 0.1524)
				(type default)
			)
			(layer "F.SilkS")
		)
		(fp_line
			(start 0.7874 -0.4064)
			(end 0.7874 0.4064)
			(stroke
				(width 0.1524)
				(type default)
			)
			(layer "F.SilkS")
		)
		(fp_line
			(start -0.67945 0.3048)
			(end -0.67945 -0.305054)
			(stroke
				(width 0.1)
				(type default)
			)
			(layer "F.Fab")
		)
		(fp_line
			(start -0.12065 0.3048)
			(end -0.67945 0.3048)
			(stroke
				(width 0.1)
				(type default)
			)
			(layer "F.Fab")
		)
		(fp_line
			(start 0.120396 0.3048)
			(end 0.120396 0.2794)
			(stroke
				(width 0.1)
				(type default)
			)
			(layer "F.Fab")
		)
		(fp_line
			(start 0.67945 0.3048)
			(end 0.120396 0.3048)
			(stroke
				(width 0.1)
				(type default)
			)
			(layer "F.Fab")
		)
		(fp_line
			(start -0.12065 0.2794)
			(end -0.12065 0.3048)
			(stroke
				(width 0.1)
				(type default)
			)
			(layer "F.Fab")
		)
		(fp_line
			(start 0.120396 0.2794)
			(end -0.12065 0.2794)
			(stroke
				(width 0.1)
				(type default)
			)
			(layer "F.Fab")
		)
		(fp_line
			(start -0.12065 -0.2794)
			(end 0.12065 -0.2794)
			(stroke
				(width 0.1)
				(type default)
			)
			(layer "F.Fab")
		)
		(fp_line
			(start 0.12065 -0.2794)
			(end 0.12065 -0.3048)
			(stroke
				(width 0.1)
				(type default)
			)
			(layer "F.Fab")
		)
		(fp_line
			(start 0.12065 -0.3048)
			(end 0.67945 -0.3048)
			(stroke
				(width 0.1)
				(type default)
			)
			(layer "F.Fab")
		)
		(fp_line
			(start 0.67945 -0.3048)
			(end 0.67945 0.3048)
			(stroke
				(width 0.1)
				(type default)
			)
			(layer "F.Fab")
		)
		(fp_line
			(start -0.67945 -0.305054)
			(end -0.12065 -0.305054)
			(stroke
				(width 0.1)
				(type default)
			)
			(layer "F.Fab")
		)
		(fp_line
			(start -0.12065 -0.305054)
			(end -0.12065 -0.2794)
			(stroke
				(width 0.1)
				(type default)
			)
			(layer "F.Fab")
		)
		(pad "1" smd circle
			(at -0.40005 0 270)
			(size 0 0)
			(layers "F.Cu" "F.Mask" "F.Paste")
			(net "NIC5_ADC_A1")
		)
		(pad "2" smd circle
			(at 0.40005 0 270)
			(size 0 0)
			(layers "F.Cu" "F.Mask" "F.Paste")
			(net "P3V3_AUX")
		)
	)
	(footprint ""
		(layer "F.Cu")
		(at 118.595394 -35.48253)
		(property "Reference" "U387"
			(at -2.566924 1.70053 90)
			(unlocked yes)
			(layer "F.SilkS")
			(effects
				(font
					(size 0.7874 0.5842)
					(thickness 0.1524)
				)
				(justify left)
			)
		)
		(property "Value" ""
			(at 0 0 0)
			(layer "F.Fab")
			(effects
				(font
					(size 1.27 1.27)
				)
			)
		)
		(duplicate_pad_numbers_are_jumpers no)
		(fp_line
			(start -1.3462 -1.1938)
			(end -1.3462 1.1684)
			(stroke
				(width 0.1524)
				(type default)
			)
			(layer "F.SilkS")
		)
		(fp_line
			(start -1.3462 1.1938)
			(end 1.3462 1.1938)
			(stroke
				(width 0.1524)
				(type default)
			)
			(layer "F.SilkS")
		)
		(fp_line
			(start 1.3462 -1.1938)
			(end -1.3462 -1.1938)
			(stroke
				(width 0.1524)
				(type default)
			)
			(layer "F.SilkS")
		)
		(fp_line
			(start 1.3462 1.1938)
			(end 1.3462 -1.1938)
			(stroke
				(width 0.1524)
				(type default)
			)
			(layer "F.SilkS")
		)
		(fp_poly
			(pts
				(xy -1.447038 -0.760476) (xy -2.052066 -0.457962) (xy -2.052066 -1.06299)
			)
			(stroke
				(width 0)
				(type default)
			)
			(fill yes)
			(layer "F.SilkS")
		)
		(fp_line
			(start -0.674878 -1.124966)
			(end -0.674878 1.124966)
			(stroke
				(width 0.1)
				(type default)
			)
			(layer "F.Fab")
		)
		(fp_line
			(start -0.674878 1.124966)
			(end 0.674878 1.124966)
			(stroke
				(width 0.1)
				(type default)
			)
			(layer "F.Fab")
		)
		(fp_line
			(start 0.674878 -1.124966)
			(end -0.674878 -1.124966)
			(stroke
				(width 0.1)
				(type default)
			)
			(layer "F.Fab")
		)
		(fp_line
			(start 0.674878 1.124966)
			(end 0.674878 -1.124966)
			(stroke
				(width 0.1)
				(type default)
			)
			(layer "F.Fab")
		)
		(fp_poly
			(pts
				(xy -1.447038 -0.760476) (xy -2.052066 -0.457962) (xy -2.052066 -1.06299)
			)
			(stroke
				(width 0)
				(type default)
			)
			(fill yes)
			(layer "F.Fab")
		)
		(pad "1" smd rect
			(at -0.899922 -0.750062)
			(size 0.6096 0.6096)
			(layers "F.Cu" "F.Mask" "F.Paste")
			(net "PWRGD_P3V3_SSD4_R")
		)
		(pad "2" smd rect
			(at -0.899922 0 90)
			(size 0.4064 0.6096)
			(layers "F.Cu" "F.Mask" "F.Paste")
			(net "RST_SMB_SSD4_N")
		)
		(pad "3" smd rect
			(at -0.899922 0.750062)
			(size 0.6096 0.6096)
			(layers "F.Cu" "F.Mask" "F.Paste")
			(net "GND")
		)
		(pad "4" smd rect
			(at 0.899922 0.750062)
			(size 0.6096 0.6096)
			(layers "F.Cu" "F.Mask" "F.Paste")
			(net "RST_SMB_SSD4_ISO_N")
		)
		(pad "5" smd rect
			(at 0.899922 -0.750062)
			(size 0.6096 0.6096)
			(layers "F.Cu" "F.Mask" "F.Paste")
			(net "P3V3_AUX")
		)
	)
	(footprint ""
		(layer "F.Cu")
		(at 320.207386 -96.811592 -90)
		(property "Reference" "R741"
			(at 0 0 270)
			(layer "F.SilkS")
			(hide yes)
			(effects
				(font
					(size 1.27 1.27)
				)
			)
		)
		(property "Value" ""
			(at 0 0 270)
			(layer "F.Fab")
			(effects
				(font
					(size 1.27 1.27)
				)
			)
		)
		(duplicate_pad_numbers_are_jumpers no)
		(fp_line
			(start -0.7874 0.4064)
			(end -0.7874 -0.4064)
			(stroke
				(width 0.1524)
				(type default)
			)
			(layer "F.SilkS")
		)
		(fp_line
			(start 0.7874 0.4064)
			(end -0.7874 0.4064)
			(stroke
				(width 0.1524)
				(type default)
			)
			(layer "F.SilkS")
		)
		(fp_line
			(start -0.7874 -0.4064)
			(end 0.7874 -0.4064)
			(stroke
				(width 0.1524)
				(type default)
			)
			(layer "F.SilkS")
		)
		(fp_line
			(start 0.7874 -0.4064)
			(end 0.7874 0.4064)
			(stroke
				(width 0.1524)
				(type default)
			)
			(layer "F.SilkS")
		)
		(fp_line
			(start -0.67945 0.3048)
			(end -0.67945 -0.305054)
			(stroke
				(width 0.1)
				(type default)
			)
			(layer "F.Fab")
		)
		(fp_line
			(start -0.12065 0.3048)
			(end -0.67945 0.3048)
			(stroke
				(width 0.1)
				(type default)
			)
			(layer "F.Fab")
		)
		(fp_line
			(start 0.120396 0.3048)
			(end 0.120396 0.2794)
			(stroke
				(width 0.1)
				(type default)
			)
			(layer "F.Fab")
		)
		(fp_line
			(start 0.67945 0.3048)
			(end 0.120396 0.3048)
			(stroke
				(width 0.1)
				(type default)
			)
			(layer "F.Fab")
		)
		(fp_line
			(start -0.12065 0.2794)
			(end -0.12065 0.3048)
			(stroke
				(width 0.1)
				(type default)
			)
			(layer "F.Fab")
		)
		(fp_line
			(start 0.120396 0.2794)
			(end -0.12065 0.2794)
			(stroke
				(width 0.1)
				(type default)
			)
			(layer "F.Fab")
		)
		(fp_line
			(start -0.12065 -0.2794)
			(end 0.12065 -0.2794)
			(stroke
				(width 0.1)
				(type default)
			)
			(layer "F.Fab")
		)
		(fp_line
			(start 0.12065 -0.2794)
			(end 0.12065 -0.3048)
			(stroke
				(width 0.1)
				(type default)
			)
			(layer "F.Fab")
		)
		(fp_line
			(start 0.12065 -0.3048)
			(end 0.67945 -0.3048)
			(stroke
				(width 0.1)
				(type default)
			)
			(layer "F.Fab")
		)
		(fp_line
			(start 0.67945 -0.3048)
			(end 0.67945 0.3048)
			(stroke
				(width 0.1)
				(type default)
			)
			(layer "F.Fab")
		)
		(fp_line
			(start -0.67945 -0.305054)
			(end -0.12065 -0.305054)
			(stroke
				(width 0.1)
				(type default)
			)
			(layer "F.Fab")
		)
		(fp_line
			(start -0.12065 -0.305054)
			(end -0.12065 -0.2794)
			(stroke
				(width 0.1)
				(type default)
			)
			(layer "F.Fab")
		)
		(pad "1" smd circle
			(at -0.40005 0 270)
			(size 0 0)
			(layers "F.Cu" "F.Mask" "F.Paste")
			(net "NIC5_ADC_A1")
		)
		(pad "2" smd circle
			(at 0.40005 0 270)
			(size 0 0)
			(layers "F.Cu" "F.Mask" "F.Paste")
			(net "GND")
		)
	)
	(footprint ""
		(layer "F.Cu")
		(at 376.936 -183.769)
		(property "Reference" "R4650"
			(at 0 0 0)
			(layer "F.SilkS")
			(hide yes)
			(effects
				(font
					(size 1.27 1.27)
				)
			)
		)
		(property "Value" ""
			(at 0 0 0)
			(layer "F.Fab")
			(effects
				(font
					(size 1.27 1.27)
				)
			)
		)
		(duplicate_pad_numbers_are_jumpers no)
		(fp_line
			(start -0.7874 -0.4064)
			(end 0.7874 -0.4064)
			(stroke
				(width 0.1524)
				(type default)
			)
			(layer "F.SilkS")
		)
		(fp_line
			(start -0.7874 0.4064)
			(end -0.7874 -0.4064)
			(stroke
				(width 0.1524)
				(type default)
			)
			(layer "F.SilkS")
		)
		(fp_line
			(start 0.7874 -0.4064)
			(end 0.7874 0.4064)
			(stroke
				(width 0.1524)
				(type default)
			)
			(layer "F.SilkS")
		)
		(fp_line
			(start 0.7874 0.4064)
			(end -0.7874 0.4064)
			(stroke
				(width 0.1524)
				(type default)
			)
			(layer "F.SilkS")
		)
		(fp_line
			(start -0.67945 -0.305054)
			(end -0.12065 -0.305054)
			(stroke
				(width 0.1)
				(type default)
			)
			(layer "F.Fab")
		)
		(fp_line
			(start -0.67945 0.3048)
			(end -0.67945 -0.305054)
			(stroke
				(width 0.1)
				(type default)
			)
			(layer "F.Fab")
		)
		(fp_line
			(start -0.12065 -0.305054)
			(end -0.12065 -0.2794)
			(stroke
				(width 0.1)
				(type default)
			)
			(layer "F.Fab")
		)
		(fp_line
			(start -0.12065 -0.2794)
			(end 0.12065 -0.2794)
			(stroke
				(width 0.1)
				(type default)
			)
			(layer "F.Fab")
		)
		(fp_line
			(start -0.12065 0.2794)
			(end -0.12065 0.3048)
			(stroke
				(width 0.1)
				(type default)
			)
			(layer "F.Fab")
		)
		(fp_line
			(start -0.12065 0.3048)
			(end -0.67945 0.3048)
			(stroke
				(width 0.1)
				(type default)
			)
			(layer "F.Fab")
		)
		(fp_line
			(start 0.120396 0.2794)
			(end -0.12065 0.2794)
			(stroke
				(width 0.1)
				(type default)
			)
			(layer "F.Fab")
		)
		(fp_line
			(start 0.120396 0.3048)
			(end 0.120396 0.2794)
			(stroke
				(width 0.1)
				(type default)
			)
			(layer "F.Fab")
		)
		(fp_line
			(start 0.12065 -0.3048)
			(end 0.67945 -0.3048)
			(stroke
				(width 0.1)
				(type default)
			)
			(layer "F.Fab")
		)
		(fp_line
			(start 0.12065 -0.2794)
			(end 0.12065 -0.3048)
			(stroke
				(width 0.1)
				(type default)
			)
			(layer "F.Fab")
		)
		(fp_line
			(start 0.67945 -0.3048)
			(end 0.67945 0.3048)
			(stroke
				(width 0.1)
				(type default)
			)
			(layer "F.Fab")
		)
		(fp_line
			(start 0.67945 0.3048)
			(end 0.120396 0.3048)
			(stroke
				(width 0.1)
				(type default)
			)
			(layer "F.Fab")
		)
		(pad "1" smd circle
			(at -0.40005 0)
			(size 0 0)
			(layers "F.Cu" "F.Mask" "F.Paste")
			(net "PRSNT_NIC1_FPGA_PCA9555_N")
		)
		(pad "2" smd circle
			(at 0.40005 0)
			(size 0 0)
			(layers "F.Cu" "F.Mask" "F.Paste")
			(net "PRSNT_NIC1_FPGA_R_N")
		)
	)
	(footprint ""
		(layer "F.Cu")
		(at 10.577322 -119.105426 90)
		(property "Reference" "R5858"
			(at 0 0 90)
			(layer "F.SilkS")
			(hide yes)
			(effects
				(font
					(size 1.27 1.27)
				)
			)
		)
		(property "Value" ""
			(at 0 0 90)
			(layer "F.Fab")
			(effects
				(font
					(size 1.27 1.27)
				)
			)
		)
		(duplicate_pad_numbers_are_jumpers no)
		(fp_line
			(start 0.7874 -0.4064)
			(end 0.7874 0.4064)
			(stroke
				(width 0.1524)
				(type default)
			)
			(layer "F.SilkS")
		)
		(fp_line
			(start -0.7874 -0.4064)
			(end 0.7874 -0.4064)
			(stroke
				(width 0.1524)
				(type default)
			)
			(layer "F.SilkS")
		)
		(fp_line
			(start 0.7874 0.4064)
			(end -0.7874 0.4064)
			(stroke
				(width 0.1524)
				(type default)
			)
			(layer "F.SilkS")
		)
		(fp_line
			(start -0.7874 0.4064)
			(end -0.7874 -0.4064)
			(stroke
				(width 0.1524)
				(type default)
			)
			(layer "F.SilkS")
		)
		(fp_line
			(start -0.12065 -0.305054)
			(end -0.12065 -0.2794)
			(stroke
				(width 0.1)
				(type default)
			)
			(layer "F.Fab")
		)
		(fp_line
			(start -0.67945 -0.305054)
			(end -0.12065 -0.305054)
			(stroke
				(width 0.1)
				(type default)
			)
			(layer "F.Fab")
		)
		(fp_line
			(start 0.67945 -0.3048)
			(end 0.67945 0.3048)
			(stroke
				(width 0.1)
				(type default)
			)
			(layer "F.Fab")
		)
		(fp_line
			(start 0.12065 -0.3048)
			(end 0.67945 -0.3048)
			(stroke
				(width 0.1)
				(type default)
			)
			(layer "F.Fab")
		)
		(fp_line
			(start 0.12065 -0.2794)
			(end 0.12065 -0.3048)
			(stroke
				(width 0.1)
				(type default)
			)
			(layer "F.Fab")
		)
		(fp_line
			(start -0.12065 -0.2794)
			(end 0.12065 -0.2794)
			(stroke
				(width 0.1)
				(type default)
			)
			(layer "F.Fab")
		)
		(fp_line
			(start 0.120396 0.2794)
			(end -0.12065 0.2794)
			(stroke
				(width 0.1)
				(type default)
			)
			(layer "F.Fab")
		)
		(fp_line
			(start -0.12065 0.2794)
			(end -0.12065 0.3048)
			(stroke
				(width 0.1)
				(type default)
			)
			(layer "F.Fab")
		)
		(fp_line
			(start 0.67945 0.3048)
			(end 0.120396 0.3048)
			(stroke
				(width 0.1)
				(type default)
			)
			(layer "F.Fab")
		)
		(fp_line
			(start 0.120396 0.3048)
			(end 0.120396 0.2794)
			(stroke
				(width 0.1)
				(type default)
			)
			(layer "F.Fab")
		)
		(fp_line
			(start -0.12065 0.3048)
			(end -0.67945 0.3048)
			(stroke
				(width 0.1)
				(type default)
			)
			(layer "F.Fab")
		)
		(fp_line
			(start -0.67945 0.3048)
			(end -0.67945 -0.305054)
			(stroke
				(width 0.1)
				(type default)
			)
			(layer "F.Fab")
		)
		(pad "1" smd circle
			(at -0.40005 0 90)
			(size 0 0)
			(layers "F.Cu" "F.Mask" "F.Paste")
			(net "PWRGD_P3V3_NIC0_D")
		)
		(pad "2" smd circle
			(at 0.40005 0 90)
			(size 0 0)
			(layers "F.Cu" "F.Mask" "F.Paste")
			(net "PWRGD_P3V3_NIC0_R")
		)
	)
	(footprint ""
		(layer "F.Cu")
		(at 189.210696 -409.795472 90)
		(property "Reference" "R4415"
			(at 0 0 90)
			(layer "F.SilkS")
			(hide yes)
			(effects
				(font
					(size 1.27 1.27)
				)
			)
		)
		(property "Value" ""
			(at 0 0 90)
			(layer "F.Fab")
			(effects
				(font
					(size 1.27 1.27)
				)
			)
		)
		(duplicate_pad_numbers_are_jumpers no)
		(fp_line
			(start 0.7874 -0.4064)
			(end 0.7874 0.4064)
			(stroke
				(width 0.1524)
				(type default)
			)
			(layer "F.SilkS")
		)
		(fp_line
			(start -0.7874 -0.4064)
			(end 0.7874 -0.4064)
			(stroke
				(width 0.1524)
				(type default)
			)
			(layer "F.SilkS")
		)
		(fp_line
			(start 0.7874 0.4064)
			(end -0.7874 0.4064)
			(stroke
				(width 0.1524)
				(type default)
			)
			(layer "F.SilkS")
		)
		(fp_line
			(start -0.7874 0.4064)
			(end -0.7874 -0.4064)
			(stroke
				(width 0.1524)
				(type default)
			)
			(layer "F.SilkS")
		)
		(fp_line
			(start -0.12065 -0.305054)
			(end -0.12065 -0.2794)
			(stroke
				(width 0.1)
				(type default)
			)
			(layer "F.Fab")
		)
		(fp_line
			(start -0.67945 -0.305054)
			(end -0.12065 -0.305054)
			(stroke
				(width 0.1)
				(type default)
			)
			(layer "F.Fab")
		)
		(fp_line
			(start 0.67945 -0.3048)
			(end 0.67945 0.3048)
			(stroke
				(width 0.1)
				(type default)
			)
			(layer "F.Fab")
		)
		(fp_line
			(start 0.12065 -0.3048)
			(end 0.67945 -0.3048)
			(stroke
				(width 0.1)
				(type default)
			)
			(layer "F.Fab")
		)
		(fp_line
			(start 0.12065 -0.2794)
			(end 0.12065 -0.3048)
			(stroke
				(width 0.1)
				(type default)
			)
			(layer "F.Fab")
		)
		(fp_line
			(start -0.12065 -0.2794)
			(end 0.12065 -0.2794)
			(stroke
				(width 0.1)
				(type default)
			)
			(layer "F.Fab")
		)
		(fp_line
			(start 0.120396 0.2794)
			(end -0.12065 0.2794)
			(stroke
				(width 0.1)
				(type default)
			)
			(layer "F.Fab")
		)
		(fp_line
			(start -0.12065 0.2794)
			(end -0.12065 0.3048)
			(stroke
				(width 0.1)
				(type default)
			)
			(layer "F.Fab")
		)
		(fp_line
			(start 0.67945 0.3048)
			(end 0.120396 0.3048)
			(stroke
				(width 0.1)
				(type default)
			)
			(layer "F.Fab")
		)
		(fp_line
			(start 0.120396 0.3048)
			(end 0.120396 0.2794)
			(stroke
				(width 0.1)
				(type default)
			)
			(layer "F.Fab")
		)
		(fp_line
			(start -0.12065 0.3048)
			(end -0.67945 0.3048)
			(stroke
				(width 0.1)
				(type default)
			)
			(layer "F.Fab")
		)
		(fp_line
			(start -0.67945 0.3048)
			(end -0.67945 -0.305054)
			(stroke
				(width 0.1)
				(type default)
			)
			(layer "F.Fab")
		)
		(pad "1" smd circle
			(at -0.40005 0 90)
			(size 0 0)
			(layers "F.Cu" "F.Mask" "F.Paste")
			(net "A_P12V_AUX_FP_TRIGGER")
		)
		(pad "2" smd circle
			(at 0.40005 0 90)
			(size 0 0)
			(layers "F.Cu" "F.Mask" "F.Paste")
			(net "P12V_AUX")
		)
	)
	(footprint ""
		(layer "F.Cu")
		(at 61.346842 -343.952322 90)
		(property "Reference" "C129"
			(at 0 0 90)
			(layer "F.SilkS")
			(hide yes)
			(effects
				(font
					(size 1.27 1.27)
				)
			)
		)
		(property "Value" ""
			(at 0 0 90)
			(layer "F.Fab")
			(effects
				(font
					(size 1.27 1.27)
				)
			)
		)
		(duplicate_pad_numbers_are_jumpers no)
		(fp_line
			(start 0.299974 -0.150114)
			(end 0.299974 0.150114)
			(stroke
				(width 0.1)
				(type default)
			)
			(layer "F.Fab")
		)
		(fp_line
			(start -0.299974 -0.150114)
			(end 0.299974 -0.150114)
			(stroke
				(width 0.1)
				(type default)
			)
			(layer "F.Fab")
		)
		(fp_line
			(start 0.299974 0.150114)
			(end -0.299974 0.150114)
			(stroke
				(width 0.1)
				(type default)
			)
			(layer "F.Fab")
		)
		(fp_line
			(start -0.299974 0.150114)
			(end -0.299974 -0.150114)
			(stroke
				(width 0.1)
				(type default)
			)
			(layer "F.Fab")
		)
		(pad "1" smd rect
			(at -0.2667 0 90)
			(size 0.3048 0.381)
			(layers "F.Cu" "F.Mask" "F.Paste")
			(net "P5E_PEX0_STN6_TX_DP<111>")
		)
		(pad "2" smd rect
			(at 0.2667 0 90)
			(size 0.3048 0.381)
			(layers "F.Cu" "F.Mask" "F.Paste")
			(net "P5E_PEX0_STN6_TX_C_DP<111>")
		)
	)
)
